(kicad_pcb
	(version 20241229)
	(generator "pcbnew")
	(generator_version "9.0")
	(general
		(thickness 1.599998)
		(legacy_teardrops no)
	)
	(paper "A4")
	(title_block
		(date "2023-02-12")
		(rev "1.1.5")
		(comment 9 "footprints 4-9 of 473")
	)
	(layers
		(0 "F.Cu" signal)
		(4 "In1.Cu" power "In1.GND")
		(6 "In2.Cu" signal)
		(8 "In3.Cu" power "In3.GND")
		(10 "In4.Cu" power "In4.VCC")
		(12 "In5.Cu" signal)
		(14 "In6.Cu" power "In6.VCC")
		(2 "B.Cu" signal)
		(9 "F.Adhes" user "F.Adhesive")
		(11 "B.Adhes" user "B.Adhesive")
		(13 "F.Paste" user)
		(15 "B.Paste" user)
		(5 "F.SilkS" user "F.Silkscreen")
		(7 "B.SilkS" user "B.Silkscreen")
		(1 "F.Mask" user)
		(3 "B.Mask" user)
		(17 "Dwgs.User" user "User.Drawings")
		(19 "Cmts.User" user "User.Comments")
		(21 "Eco1.User" user "User.Eco1")
		(23 "Eco2.User" user "User.Eco2")
		(25 "Edge.Cuts" user)
		(27 "Margin" user)
		(31 "F.CrtYd" user "F.Courtyard")
		(29 "B.CrtYd" user "B.Courtyard")
		(35 "F.Fab" user)
		(33 "B.Fab" user)
	)
	(footprint "antmicro-footprints:TP_SMD_1mm"
		(layer "F.Cu")
		(at 152.01 119.16 90)
		(property "Reference" "TP2"
			(at 0.36 0.0008 90)
			(layer "F.SilkS")
			(effects
				(font
					(size 0.7 0.7)
					(thickness 0.15)
				)
				(justify left bottom)
			)
		)
		(property "Value" "TP_1mm_SMD"
			(at 0 1.4 90)
			(layer "F.Fab")
			(effects
				(font
					(size 0.7 0.7)
					(thickness 0.15)
				)
				(justify left bottom)
			)
		)
		(property "Description" "Test Point 1mm"
			(at 0 0 90)
			(layer "F.Fab")
			(hide yes)
			(effects
				(font
					(size 1.27 1.27)
					(thickness 0.15)
				)
			)
		)
		(property "Author" "Antmicro"
			(at 271.17 -32.85 0)
			(layer "F.Fab")
			(hide yes)
			(effects
				(font
					(size 1 1)
					(thickness 0.15)
				)
			)
		)
		(property "License" "Apache-2.0"
			(at 271.17 -32.85 0)
			(layer "F.Fab")
			(hide yes)
			(effects
				(font
					(size 1 1)
					(thickness 0.15)
				)
			)
		)
		(property "MPN" ""
			(at 271.17 -32.85 0)
			(layer "F.Fab")
			(hide yes)
			(effects
				(font
					(size 1 1)
					(thickness 0.15)
				)
			)
		)
		(property "Manufacturer" ""
			(at 271.17 -32.85 0)
			(layer "F.Fab")
			(hide yes)
			(effects
				(font
					(size 1 1)
					(thickness 0.15)
				)
			)
		)
		(sheetname "Interfaces")
		(sheetfile "interfaces.kicad_sch")
		(attr exclude_from_pos_files)
		(pad "1" smd circle
			(at 0 0 90)
			(size 1 1)
			(layers "F.Cu" "F.Mask")
			(net 80 "Net-(J2-CEC)")
			(pinfunction "1")
			(pintype "passive")
		)
	)
	(footprint "antmicro-footprints:C_0402_1005Metric"
		(layer "F.Cu")
		(at 138.286328 115.107157)
		(descr "Capacitor SMD 0402")
		(tags "capacitor SMD 0402")
		(property "Reference" "C18"
			(at -3.286328 -0.7 0)
			(layer "F.SilkS")
			(effects
				(font
					(size 0.7 0.7)
					(thickness 0.15)
				)
				(justify left bottom)
			)
		)
		(property "Value" "C_4u7_0402"
			(at 0 1.4 0)
			(layer "F.Fab")
			(effects
				(font
					(size 0.7 0.7)
					(thickness 0.15)
				)
				(justify left bottom)
			)
		)
		(property "Description" " "
			(at 0 0 0)
			(layer "F.Fab")
			(hide yes)
			(effects
				(font
					(size 1.27 1.27)
					(thickness 0.15)
				)
			)
		)
		(property "Author" "Antmicro"
			(at 0 0 0)
			(layer "F.Fab")
			(hide yes)
			(effects
				(font
					(size 1 1)
					(thickness 0.15)
				)
			)
		)
		(property "Dielectric" ""
			(at 0 0 0)
			(layer "F.Fab")
			(hide yes)
			(effects
				(font
					(size 1 1)
					(thickness 0.15)
				)
			)
		)
		(property "License" "Apache-2.0"
			(at 0 0 0)
			(layer "F.Fab")
			(hide yes)
			(effects
				(font
					(size 1 1)
					(thickness 0.15)
				)
			)
		)
		(property "MPN" "GRM155R61A475MEAAD"
			(at 0 0 0)
			(layer "F.Fab")
			(hide yes)
			(effects
				(font
					(size 1 1)
					(thickness 0.15)
				)
			)
		)
		(property "Manufacturer" "Murata"
			(at 0 0 0)
			(layer "F.Fab")
			(hide yes)
			(effects
				(font
					(size 1 1)
					(thickness 0.15)
				)
			)
		)
		(property "Val" "4u7"
			(at 0 0 0)
			(layer "F.Fab")
			(hide yes)
			(effects
				(font
					(size 1 1)
					(thickness 0.15)
				)
			)
		)
		(property "Voltage" ""
			(at 0 0 0)
			(layer "F.Fab")
			(hide yes)
			(effects
				(font
					(size 1 1)
					(thickness 0.15)
				)
			)
		)
		(sheetname "Interfaces")
		(sheetfile "interfaces.kicad_sch")
		(attr smd)
		(fp_rect
			(start -0.94 -0.47)
			(end 0.94 0.47)
			(stroke
				(width 0.05)
				(type solid)
			)
			(fill no)
			(layer "F.CrtYd")
		)
		(fp_rect
			(start -0.499 -0.249)
			(end 0.499 0.249)
			(stroke
				(width 0.15)
				(type solid)
			)
			(fill no)
			(layer "F.Fab")
		)
		(pad "1" smd roundrect
			(at -0.484 0)
			(size 0.59 0.64)
			(layers "F.Cu" "F.Mask" "F.Paste")
			(roundrect_rratio 0.25)
			(net 5 "GND")
			(pintype "passive")
		)
		(pad "2" smd roundrect
			(at 0.484 0)
			(size 0.59 0.64)
			(layers "F.Cu" "F.Mask" "F.Paste")
			(roundrect_rratio 0.25)
			(net 653 "/Interfaces/VPHY")
			(pintype "passive")
		)
	)
	(footprint "antmicro-footprints:R_0402_1005Metric"
		(layer "F.Cu")
		(at 145.046328 114.596157 90)
		(descr "Resistor SMD 0402")
		(tags "resistor SMD 0402")
		(property "Reference" "R8"
			(at -0.803843 1.253672 90)
			(layer "F.SilkS")
			(effects
				(font
					(size 0.7 0.7)
					(thickness 0.15)
				)
				(justify left bottom)
			)
		)
		(property "Value" "R_10k_0402"
			(at 0 1.4 90)
			(layer "F.Fab")
			(effects
				(font
					(size 0.7 0.7)
					(thickness 0.15)
				)
				(justify left bottom)
			)
		)
		(property "Description" "10k resistor in 0402 package with 1% tolerance"
			(at 0 0 90)
			(layer "F.Fab")
			(hide yes)
			(effects
				(font
					(size 1.27 1.27)
					(thickness 0.15)
				)
			)
		)
		(property "Author" "Antmicro"
			(at 259.642485 -30.450171 0)
			(layer "F.Fab")
			(hide yes)
			(effects
				(font
					(size 1 1)
					(thickness 0.15)
				)
			)
		)
		(property "License" "Apache-2.0"
			(at 259.642485 -30.450171 0)
			(layer "F.Fab")
			(hide yes)
			(effects
				(font
					(size 1 1)
					(thickness 0.15)
				)
			)
		)
		(property "MPN" "CR0402-FX-1002GLF"
			(at 259.642485 -30.450171 0)
			(layer "F.Fab")
			(hide yes)
			(effects
				(font
					(size 1 1)
					(thickness 0.15)
				)
			)
		)
		(property "Manufacturer" "Bourns"
			(at 259.642485 -30.450171 0)
			(layer "F.Fab")
			(hide yes)
			(effects
				(font
					(size 1 1)
					(thickness 0.15)
				)
			)
		)
		(property "Tolerance" "1%"
			(at 259.642485 -30.450171 0)
			(layer "F.Fab")
			(hide yes)
			(effects
				(font
					(size 1 1)
					(thickness 0.15)
				)
			)
		)
		(property "Val" "10k"
			(at 259.642485 -30.450171 0)
			(layer "F.Fab")
			(hide yes)
			(effects
				(font
					(size 1 1)
					(thickness 0.15)
				)
			)
		)
		(sheetname "Interfaces")
		(sheetfile "interfaces.kicad_sch")
		(attr smd)
		(fp_rect
			(start -0.93 -0.47)
			(end 0.93 0.47)
			(stroke
				(width 0.05)
				(type solid)
			)
			(fill no)
			(layer "F.CrtYd")
		)
		(fp_rect
			(start -0.5 -0.25)
			(end 0.5 0.25)
			(stroke
				(width 0.15)
				(type solid)
			)
			(fill no)
			(layer "F.Fab")
		)
		(pad "1" smd roundrect
			(at -0.485 0 90)
			(size 0.59 0.64)
			(layers "F.Cu" "F.Mask" "F.Paste")
			(roundrect_rratio 0.25)
			(net 459 "3V3_SYS")
			(pintype "passive")
		)
		(pad "2" smd roundrect
			(at 0.485 0 90)
			(size 0.59 0.64)
			(layers "F.Cu" "F.Mask" "F.Paste")
			(roundrect_rratio 0.25)
			(net 240 "Net-(U4-~{RESET})")
			(pintype "passive")
		)
	)
	(footprint "antmicro-footprints:C_0402_1005Metric"
		(layer "F.Cu")
		(at 135.1 112.099)
		(descr "Capacitor SMD 0402")
		(tags "capacitor SMD 0402")
		(property "Reference" "C13"
			(at -1.1 1.301 0)
			(layer "F.SilkS")
			(effects
				(font
					(size 0.7 0.7)
					(thickness 0.15)
				)
				(justify left bottom)
			)
		)
		(property "Value" "C_100n_6V3_0402"
			(at 0 1.4 0)
			(layer "F.Fab")
			(effects
				(font
					(size 0.7 0.7)
					(thickness 0.15)
				)
				(justify left bottom)
			)
		)
		(property "Description" " "
			(at 0 0 0)
			(layer "F.Fab")
			(hide yes)
			(effects
				(font
					(size 1.27 1.27)
					(thickness 0.15)
				)
			)
		)
		(property "Author" "Antmicro"
			(at 0 0 0)
			(layer "F.Fab")
			(hide yes)
			(effects
				(font
					(size 1 1)
					(thickness 0.15)
				)
			)
		)
		(property "Dielectric" ""
			(at 0 0 0)
			(layer "F.Fab")
			(hide yes)
			(effects
				(font
					(size 1 1)
					(thickness 0.15)
				)
			)
		)
		(property "License" "Apache-2.0"
			(at 0 0 0)
			(layer "F.Fab")
			(hide yes)
			(effects
				(font
					(size 1 1)
					(thickness 0.15)
				)
			)
		)
		(property "MPN" "0402X104K6R3CT"
			(at 0 0 0)
			(layer "F.Fab")
			(hide yes)
			(effects
				(font
					(size 1 1)
					(thickness 0.15)
				)
			)
		)
		(property "Manufacturer" "Walsin"
			(at 0 0 0)
			(layer "F.Fab")
			(hide yes)
			(effects
				(font
					(size 1 1)
					(thickness 0.15)
				)
			)
		)
		(property "Val" "100n"
			(at 0 0 0)
			(layer "F.Fab")
			(hide yes)
			(effects
				(font
					(size 1 1)
					(thickness 0.15)
				)
			)
		)
		(property "Voltage" ""
			(at 0 0 0)
			(layer "F.Fab")
			(hide yes)
			(effects
				(font
					(size 1 1)
					(thickness 0.15)
				)
			)
		)
		(sheetname "Interfaces")
		(sheetfile "interfaces.kicad_sch")
		(attr smd)
		(fp_rect
			(start -0.94 -0.47)
			(end 0.94 0.47)
			(stroke
				(width 0.05)
				(type solid)
			)
			(fill no)
			(layer "F.CrtYd")
		)
		(fp_rect
			(start -0.499 -0.249)
			(end 0.499 0.249)
			(stroke
				(width 0.15)
				(type solid)
			)
			(fill no)
			(layer "F.Fab")
		)
		(pad "1" smd roundrect
			(at -0.484 0)
			(size 0.59 0.64)
			(layers "F.Cu" "F.Mask" "F.Paste")
			(roundrect_rratio 0.25)
			(net 5 "GND")
			(pintype "passive")
		)
		(pad "2" smd roundrect
			(at 0.484 0)
			(size 0.59 0.64)
			(layers "F.Cu" "F.Mask" "F.Paste")
			(roundrect_rratio 0.25)
			(net 2 "/Interfaces/1V8_FT")
			(pintype "passive")
		)
	)
	(footprint "antmicro-footprints:Resonator_SMD_Abracon_ABM8G_3.2x2.5mm"
		(layer "F.Cu")
		(at 135.161328 116.621157 -90)
		(property "Reference" "Y1"
			(at 3.012843 0.795328 0)
			(layer "F.SilkS")
			(effects
				(font
					(size 0.7 0.7)
					(thickness 0.15)
				)
				(justify left bottom)
			)
		)
		(property "Value" "Oscillator_SMD_12MHz_KX-7"
			(at -1.75 2.548 270)
			(layer "F.Fab")
			(effects
				(font
					(size 0.7 0.7)
					(thickness 0.15)
				)
				(justify left bottom)
			)
		)
		(property "Description" "Crystal, 12 MHz, SMT, 3.2mm x 2.5mm, 30 ppm, 18 pF, 20 ppm, ABM8G"
			(at 0 0 270)
			(layer "F.Fab")
			(hide yes)
			(effects
				(font
					(size 1.27 1.27)
					(thickness 0.15)
				)
			)
		)
		(property "Author" "Antmicro"
			(at 18.540171 251.782485 0)
			(layer "F.Fab")
			(hide yes)
			(effects
				(font
					(size 1 1)
					(thickness 0.15)
				)
			)
		)
		(property "License" "Apache-2.0"
			(at 18.540171 251.782485 0)
			(layer "F.Fab")
			(hide yes)
			(effects
				(font
					(size 1 1)
					(thickness 0.15)
				)
			)
		)
		(property "MPN" "ABM8G-12.000MHZ-18-D2Y-T"
			(at 18.540171 251.782485 0)
			(layer "F.Fab")
			(hide yes)
			(effects
				(font
					(size 1 1)
					(thickness 0.15)
				)
			)
		)
		(property "Manufacturer" "Abracon"
			(at 18.540171 251.782485 0)
			(layer "F.Fab")
			(hide yes)
			(effects
				(font
					(size 1 1)
					(thickness 0.15)
				)
			)
		)
		(property "Val" "12 MHz"
			(at 18.540171 251.782485 0)
			(layer "F.Fab")
			(hide yes)
			(effects
				(font
					(size 1 1)
					(thickness 0.15)
				)
			)
		)
		(sheetname "Interfaces")
		(sheetfile "interfaces.kicad_sch")
		(attr smd)
		(fp_line
			(start -0.35 1.25)
			(end 0.45 1.25)
			(stroke
				(width 0.15)
				(type solid)
			)
			(layer "F.SilkS")
		)
		(fp_line
			(start -1.6 0.3)
			(end -1.6 -0.2)
			(stroke
				(width 0.15)
				(type solid)
			)
			(layer "F.SilkS")
		)
		(fp_line
			(start 1.6 0.3)
			(end 1.6 -0.2)
			(stroke
				(width 0.15)
				(type solid)
			)
			(layer "F.SilkS")
		)
		(fp_line
			(start -0.35 -1.25)
			(end 0.45 -1.25)
			(stroke
				(width 0.15)
				(type solid)
			)
			(layer "F.SilkS")
		)
		(fp_circle
			(center -1.75 1.5)
			(end -1.7 1.5)
			(stroke
				(width 0.15)
				(type solid)
			)
			(fill no)
			(layer "F.SilkS")
		)
		(fp_rect
			(start -1.907 -1.55)
			(end 2.006 1.649)
			(stroke
				(width 0.05)
				(type solid)
			)
			(fill no)
			(layer "F.CrtYd")
		)
		(pad "1" smd roundrect
			(at -1.101 0.949 270)
			(size 1.3 1.1)
			(layers "F.Cu" "F.Mask" "F.Paste")
			(roundrect_rratio 0)
			(chamfer_ratio 0.2)
			(chamfer bottom_left)
			(net 3 "Net-(U4-OSCI)")
			(pintype "passive")
		)
		(pad "2" smd rect
			(at 1.199 0.949 270)
			(size 1.3 1.1)
			(layers "F.Cu" "F.Mask" "F.Paste")
			(net 5 "GND")
			(pinfunction "SH")
			(pintype "passive")
		)
		(pad "3" smd rect
			(at 1.199 -0.85 270)
			(size 1.3 1.1)
			(layers "F.Cu" "F.Mask" "F.Paste")
			(net 4 "Net-(U4-OSCO)")
			(pintype "passive")
		)
		(pad "4" smd rect
			(at -1.101 -0.85 270)
			(size 1.3 1.1)
			(layers "F.Cu" "F.Mask" "F.Paste")
			(net 5 "GND")
			(pinfunction "SH")
			(pintype "passive")
		)
	)
	(footprint "antmicro-footprints:USB-Micro-B_Receptacle_WE_629105150521"
		(layer "F.Cu")
		(at 136.236328 132.796157)
		(descr "USB Micro-B receptacle")
		(tags "usb micro receptacle")
		(property "Reference" "J1"
			(at 3.209672 -4.526157 0)
			(layer "F.SilkS")
			(effects
				(font
					(size 0.7 0.7)
					(thickness 0.15)
				)
				(justify left)
			)
		)
		(property "Value" "USB-Micro-B_629105150521"
			(at 0 4.3 0)
			(layer "F.Fab")
			(effects
				(font
					(size 0.7 0.7)
					(thickness 0.15)
				)
				(justify left bottom)
			)
		)
		(property "Description" "USB - micro B USB 2.0 Receptacle Connector 5 Position Surface Mount, Right Angle"
			(at 0 0 0)
			(layer "F.Fab")
			(hide yes)
			(effects
				(font
					(size 1.27 1.27)
					(thickness 0.15)
				)
			)
		)
		(property "Author" "Antmicro"
			(at 0 0 0)
			(layer "F.Fab")
			(hide yes)
			(effects
				(font
					(size 1 1)
					(thickness 0.15)
				)
			)
		)
		(property "License" "Apache-2.0"
			(at 0 0 0)
			(layer "F.Fab")
			(hide yes)
			(effects
				(font
					(size 1 1)
					(thickness 0.15)
				)
			)
		)
		(property "MPN" "629105150521"
			(at 0 0 0)
			(layer "F.Fab")
			(hide yes)
			(effects
				(font
					(size 1 1)
					(thickness 0.15)
				)
			)
		)
		(property "Manufacturer" "Würth Elektronik"
			(at 0 0 0)
			(layer "F.Fab")
			(hide yes)
			(effects
				(font
					(size 1 1)
					(thickness 0.15)
				)
			)
		)
		(sheetname "Interfaces")
		(sheetfile "interfaces.kicad_sch")
		(attr smd)
		(fp_line
			(start -4.151 -1.7)
			(end -4.151 -0.299)
			(stroke
				(width 0.15)
				(type solid)
			)
			(layer "F.SilkS")
		)
		(fp_line
			(start -4.151 2.1)
			(end -4.151 2.25)
			(stroke
				(width 0.15)
				(type solid)
			)
			(layer "F.SilkS")
		)
		(fp_line
			(start -4.151 2.25)
			(end -3.851 2.25)
			(stroke
				(width 0.15)
				(type solid)
			)
			(layer "F.SilkS")
		)
		(fp_line
			(start -3.851 2.25)
			(end -3.851 2.701)
			(stroke
				(width 0.15)
				(type solid)
			)
			(layer "F.SilkS")
		)
		(fp_line
			(start -2.85 -3.5)
			(end -1.852 -3.5)
			(stroke
				(width 0.15)
				(type solid)
			)
			(layer "F.SilkS")
		)
		(fp_line
			(start 1.8 -3.45)
			(end 2.798 -3.45)
			(stroke
				(width 0.15)
				(type solid)
			)
			(layer "F.SilkS")
		)
		(fp_line
			(start 3.85 2.25)
			(end 4.15 2.25)
			(stroke
				(width 0.15)
				(type solid)
			)
			(layer "F.SilkS")
		)
		(fp_line
			(start 3.85 2.701)
			(end 3.85 2.25)
			(stroke
				(width 0.15)
				(type solid)
			)
			(layer "F.SilkS")
		)
		(fp_line
			(start 4.15 -0.299)
			(end 4.15 -1.7)
			(stroke
				(width 0.15)
				(type solid)
			)
			(layer "F.SilkS")
		)
		(fp_line
			(start 4.15 2.25)
			(end 4.15 2.1)
			(stroke
				(width 0.15)
				(type solid)
			)
			(layer "F.SilkS")
		)
		(fp_circle
			(center -1.7 -3.7)
			(end -1.65 -3.65)
			(stroke
				(width 0.15)
				(type solid)
			)
			(fill yes)
			(layer "F.SilkS")
		)
		(fp_rect
			(start -4.5 -3.95)
			(end 4.5 3.4)
			(stroke
				(width 0.05)
				(type solid)
			)
			(fill no)
			(layer "F.CrtYd")
		)
		(fp_line
			(start -4 -3.299)
			(end -4 2.1)
			(stroke
				(width 0.15)
				(type solid)
			)
			(layer "F.Fab")
		)
		(fp_line
			(start -4 2.1)
			(end -3.701 2.1)
			(stroke
				(width 0.15)
				(type solid)
			)
			(layer "F.Fab")
		)
		(fp_line
			(start -3.701 2.1)
			(end -3.701 3.301)
			(stroke
				(width 0.15)
				(type solid)
			)
			(layer "F.Fab")
		)
		(fp_line
			(start -3.701 3.301)
			(end 3.7 3.301)
			(stroke
				(width 0.15)
				(type solid)
			)
			(layer "F.Fab")
		)
		(fp_line
			(start 3.7 2.1)
			(end 3.999 2.1)
			(stroke
				(width 0.15)
				(type solid)
			)
			(layer "F.Fab")
		)
		(fp_line
			(start 3.7 3.301)
			(end 3.7 2.1)
			(stroke
				(width 0.15)
				(type solid)
			)
			(layer "F.Fab")
		)
		(fp_line
			(start 3.999 -3.299)
			(end -4 -3.299)
			(stroke
				(width 0.15)
				(type solid)
			)
			(layer "F.Fab")
		)
		(fp_line
			(start 3.999 2.1)
			(end 3.999 -3.299)
			(stroke
				(width 0.15)
				(type solid)
			)
			(layer "F.Fab")
		)
		(pad "" np_thru_hole oval
			(at -2.5 -1.849)
			(size 0.8 0.8)
			(drill 0.8)
			(layers "*.Cu" "*.Mask")
		)
		(pad "" np_thru_hole oval
			(at 2.499 -1.849)
			(size 0.8 0.8)
			(drill 0.8)
			(layers "*.Cu" "*.Mask")
		)
		(pad "1" smd roundrect
			(at -1.301 -2.949)
			(size 0.45 1.3)
			(layers "F.Cu" "F.Mask" "F.Paste")
			(roundrect_rratio 0.25)
			(net 1 "VBUS")
			(pinfunction "VBUS")
			(pintype "passive")
		)
		(pad "2" smd roundrect
			(at -0.652 -2.949)
			(size 0.45 1.3)
			(layers "F.Cu" "F.Mask" "F.Paste")
			(roundrect_rratio 0.25)
			(net 7 "DBG_USB_N")
			(pinfunction "D-")
			(pintype "bidirectional")
		)
		(pad "3" smd roundrect
			(at 0 -2.949)
			(size 0.45 1.3)
			(layers "F.Cu" "F.Mask" "F.Paste")
			(roundrect_rratio 0.25)
			(net 6 "DBG_USB_P")
			(pinfunction "D+")
			(pintype "bidirectional")
		)
		(pad "4" smd roundrect
			(at 0.65 -2.949)
			(size 0.45 1.3)
			(layers "F.Cu" "F.Mask" "F.Paste")
			(roundrect_rratio 0.25)
			(net 78 "unconnected-(J1-ID-Pad4)")
			(pinfunction "ID")
			(pintype "bidirectional+no_connect")
		)
		(pad "5" smd roundrect
			(at 1.3 -2.949)
			(size 0.45 1.3)
			(layers "F.Cu" "F.Mask" "F.Paste")
			(roundrect_rratio 0.25)
			(net 5 "GND")
			(pinfunction "GND")
			(pintype "power_in")
		)
		(pad "SH" thru_hole oval
			(at -3.875 0.901)
			(size 1.15 1.8)
			(drill oval 0.55 1.2)
			(layers "*.Cu" "*.Mask")
			(remove_unused_layers no)
			(net 74 "Net-(J1-SHIELD)")
			(pinfunction "SHIELD")
			(pintype "passive")
		)
		(pad "SH" thru_hole oval
			(at -3.726 -2.899)
			(size 1.45 2)
			(drill oval 0.85 1.4)
			(layers "*.Cu" "*.Mask")
			(remove_unused_layers no)
			(net 74 "Net-(J1-SHIELD)")
			(pinfunction "SHIELD")
			(pintype "passive")
		)
		(pad "SH" thru_hole oval
			(at 3.725 -2.899)
			(size 1.45 2)
			(drill oval 0.85 1.4)
			(layers "*.Cu" "*.Mask")
			(remove_unused_layers no)
			(net 74 "Net-(J1-SHIELD)")
			(pinfunction "SHIELD")
			(pintype "passive")
		)
		(pad "SH" thru_hole oval
			(at 3.874 0.901)
			(size 1.15 1.8)
			(drill oval 0.55 1.2)
			(layers "*.Cu" "*.Mask")
			(remove_unused_layers no)
			(net 74 "Net-(J1-SHIELD)")
			(pinfunction "SHIELD")
			(pintype "passive")
		)
	)
)
